# T6G (Grand Teton) — schematic parts with pin connectivity, parts 8234–8237 of 8303; source: Cadence DE-HDL packaged netlist (pstxprt.dat, pstxnet.dat, pstchip.dat)

U6017  PT5161LRS  IC  pkg BGA354_8-9X22-8  page 351
  A1  NCF_GND1  POWER  = NCF_A1_CPU1_P3_GND
  A35  NCF_GND2  POWER  = NCF_CPU1_P3_GND
  AA10  B_PETN1  OUT  = P5E_CPU1_P3_TX_BUF_DN<14>
  AA29  A_PETN1  OUT  = P5E_CPU1_P3_RX_DN<14>
  AB1  A_PERP1  IN  = P5E_CPU1_P3_RX_BUF_DP<14>
  AB35  B_PERN1  IN  = P5E_CPU1_P3_TX_C_DN<14>
  AC4  GND4  POWER  = GND
  AC13  GND1  POWER  = GND
  AC17  PWR_2A_1  POWER  = P0V9_CPU1_RT3_2A
  AC20  PWR_2A_2  POWER  = P0V9_CPU1_RT3_2A
  AC22  GND2  POWER  = GND
  AC32  GND3  POWER  = GND
  AD2  GND5  POWER  = GND
  AD34  GND6  POWER  = GND
  AE1  GND7  POWER  = GND
  AE35  GND8  POWER  = GND
  AF7  B_PETP2  OUT  = P5E_CPU1_P3_TX_BUF_DP<13>
  AF26  A_PETP2  OUT  = P5E_CPU1_P3_RX_DP<13>
  AG2  A_PERN2  IN  = P5E_CPU1_P3_RX_BUF_DN<13>
  AG34  B_PERP2  IN  = P5E_CPU1_P3_TX_C_DN<13>
  AH10  B_PETN2  OUT  = P5E_CPU1_P3_TX_BUF_DN<13>
  AH29  A_PETN2  OUT  = P5E_CPU1_P3_RX_DN<13>
  AJ1  A_PERP2  IN  = P5E_CPU1_P3_RX_BUF_DP<13>
  AJ35  B_PERN2  IN  = P5E_CPU1_P3_TX_C_DP<13>
  AK4  GND12  POWER  = GND
  AK13  GND9  POWER  = GND
  AK17  PWR_2A_3  POWER  = P0V9_CPU1_RT3_2A
  AK20  PWR_2A_4  POWER  = P0V9_CPU1_RT3_2A
  AK22  GND10  POWER  = GND
  AK32  GND11  POWER  = GND
  AL2  GND13  POWER  = GND
  AL34  GND14  POWER  = GND
  AM1  GND15  POWER  = GND
  AM35  GND16  POWER  = GND
  AN7  B_PETP3  OUT  = P5E_CPU1_P3_TX_BUF_DP<12>
  AN26  A_PETP3  OUT  = P5E_CPU1_P3_RX_DP<12>
  AP2  A_PERN3  IN  = P5E_CPU1_P3_RX_BUF_DN<12>
  AP34  B_PERP3  IN  = P5E_CPU1_P3_TX_C_DN<12>
  AR10  B_PETN3  OUT  = P5E_CPU1_P3_TX_BUF_DN<12>
  AR29  A_PETN3  OUT  = P5E_CPU1_P3_RX_DN<12>
  AT1  A_PERP3  IN  = P5E_CPU1_P3_RX_BUF_DP<12>
  AT35  B_PERN3  IN  = P5E_CPU1_P3_TX_C_DP<12>
  AU4  GND20  POWER  = GND
  AU13  GND17  POWER  = GND
  AU17  PWR_2A_5  POWER  = P0V9_CPU1_RT3_2A
  AU20  PWR_2A_6  POWER  = P0V9_CPU1_RT3_2A
  AU22  GND18  POWER  = GND
  AU32  GND19  POWER  = GND
  AV2  GND21  POWER  = GND
  AV34  GND22  POWER  = GND
  AW1  GND23  POWER  = GND
  AW35  GND24  POWER  = GND
  AY7  B_PETP4  OUT  = P5E_CPU1_P3_TX_BUF_DP<11>
  AY26  A_PETP4  OUT  = P5E_CPU1_P3_RX_DP<11>
  B3  JTAG_TCK  IN  = JTAG_TCK_RT_CPU1_P3
  B6  JTAG_TDI  IN  = JTAG_TDI_RT_CPU1_P3
  B9  JTAG_TDO  OUT  = JTAG_TDO_RT_CPU1_P3
  B12  JTAG_TMS  IN  = JTAG_TMS_RT_CPU1_P3
  B16  REFCLK_OUTP  OUT  = NC
  B19  GND25  POWER  = GND
  B23  SMB_ADDR2  IN  = RT_CPU1_P3_ADDR2
  B25  SMB_ADDR3  IN  = RT_CPU1_P3_ADDR3
  B28  SMBDAT  BI  = SMB_RT_CPU1_P3_R2_SDA
  B31  SMBCLK  BI  = SMB_RT_CPU1_P3_R2_SCL
  BA2  A_PERN4  IN  = P5E_CPU1_P3_RX_BUF_DN<11>
  BA34  B_PERP4  IN  = P5E_CPU1_P3_TX_C_DN<11>
  BB10  B_PETN4  OUT  = P5E_CPU1_P3_TX_BUF_DN<11>
  BB29  A_PETN4  OUT  = P5E_CPU1_P3_RX_DN<11>
  BC1  A_PERP4  IN  = P5E_CPU1_P3_RX_BUF_DP<11>
  BC35  B_PERN4  IN  = P5E_CPU1_P3_TX_C_DP<11>
  BD4  GND29  POWER  = GND
  BD13  GND26  POWER  = GND
  BD17  PWR_2A_7  POWER  = P0V9_CPU1_RT3_2A_2D
  BD20  PWR_2A_8  POWER  = P0V9_CPU1_RT3_2A_2D
  BD22  GND27  POWER  = GND
  BD32  GND28  POWER  = GND
  BE2  GND30  POWER  = GND
  BE34  GND31  POWER  = GND
  BF1  GND32  POWER  = GND
  BF35  GND33  POWER  = GND
  BG7  B_PETP5  OUT  = P5E_CPU1_P3_TX_BUF_DP<10>
  BG26  A_PETP5  OUT  = P5E_CPU1_P3_RX_DP<10>
  BH2  A_PERN5  IN  = P5E_CPU1_P3_RX_BUF_DN<10>
  BH34  B_PERP5  IN  = P5E_CPU1_P3_TX_C_DN<10>
  BJ10  B_PETN5  OUT  = P5E_CPU1_P3_TX_BUF_DN<10>
  BJ29  A_PETN5  OUT  = P5E_CPU1_P3_RX_DN<10>
  BK1  A_PERP5  IN  = P5E_CPU1_P3_RX_BUF_DP<10>
  BK35  B_PERN5  IN  = P5E_CPU1_P3_TX_C_DP<10>
  BL4  GND37  POWER  = GND
  BL13  GND34  POWER  = GND
  BL17  PWR_2D_1  POWER  = P0V9_CPU1_RT_2D
  BL20  PWR_2D_2  POWER  = P0V9_CPU1_RT_2D
  BL22  GND35  POWER  = GND
  BL32  GND36  POWER  = GND
  BM2  GND38  POWER  = GND
  BM34  GND39  POWER  = GND
  BN1  GND40  POWER  = GND
  BN35  GND41  POWER  = GND
  BP7  B_PETP6  OUT  = P5E_CPU1_P3_TX_BUF_DP<9>
  BP26  A_PETP6  OUT  = P5E_CPU1_P3_RX_DP<9>
  BR2  A_PERN6  IN  = P5E_CPU1_P3_RX_BUF_DN<9>
  BR34  B_PERP6  IN  = P5E_CPU1_P3_TX_C_DN<9>
  BT10  B_PETN6  OUT  = P5E_CPU1_P3_TX_BUF_DN<9>
  BT29  A_PETN6  OUT  = P5E_CPU1_P3_RX_DN<9>
  BU1  A_PERP6  IN  = P5E_CPU1_P3_RX_BUF_DP<9>
  BU35  B_PERN6  IN  = P5E_CPU1_P3_TX_C_DP<9>
  BV4  GND45  POWER  = GND
  BV13  GND42  POWER  = GND
  BV17  PWR_1D  POWER  = P1V8_CPU1_RT3_1A_1D
  BV20  PWR_1A_1  POWER  = P1V8_CPU1_RT3_1A
  BV22  GND43  POWER  = GND
  BV32  GND44  POWER  = GND
  BW2  GND46  POWER  = GND
  BW34  GND47  POWER  = GND
  BY1  GND48  POWER  = GND
  BY35  GND49  POWER  = GND
  C2  NCF_GND3  POWER  = NCF_CPU1_P3_GND
  C34  NCF_GND4  POWER  = NCF_CPU1_P3_GND
  CA7  B_PETP7  OUT  = P5E_CPU1_P3_TX_BUF_DP<8>
  CA26  A_PETP7  OUT  = P5E_CPU1_P3_RX_DP<8>
  CB2  A_PERN7  IN  = P5E_CPU1_P3_RX_BUF_DN<8>
  CB34  B_PERP7  IN  = P5E_CPU1_P3_TX_C_DN<8>
  CC10  B_PETN7  OUT  = P5E_CPU1_P3_TX_BUF_DN<8>
  CC29  A_PETN7  OUT  = P5E_CPU1_P3_RX_DN<8>
  CD1  A_PERP7  IN  = P5E_CPU1_P3_RX_BUF_DP<8>
  CD35  B_PERN7  IN  = P5E_CPU1_P3_TX_C_DP<8>
  CE4  GND53  POWER  = GND
  CE13  GND50  POWER  = GND
  CE17  PWR_1A_2  POWER  = P1V8_CPU1_RT3_1A
  CE20  PWR_1A_3  POWER  = P1V8_CPU1_RT3_1A
  CE22  GND51  POWER  = GND
  CE32  GND52  POWER  = GND
  CF2  GND54  POWER  = GND
  CF34  GND55  POWER  = GND
  CG1  GND56  POWER  = GND
  CG35  GND57  POWER  = GND
  CH7  B_PETP8  OUT  = P5E_CPU1_P3_TX_BUF_DP<7>
  CH26  A_PETP8  OUT  = P5E_CPU1_P3_RX_DP<7>
  CJ2  A_PERN8  IN  = P5E_CPU1_P3_RX_BUF_DN<7>
  CJ34  B_PERP8  IN  = P5E_CPU1_P3_TX_C_DN<7>
  CK10  B_PETN8  OUT  = P5E_CPU1_P3_TX_BUF_DN<7>
  CK29  A_PETN8  OUT  = P5E_CPU1_P3_RX_DN<7>
  CL1  A_PERP8  IN  = P5E_CPU1_P3_RX_BUF_DP<7>
  CL35  B_PERN8  IN  = P5E_CPU1_P3_TX_C_DP<7>
  CM4  GND61  POWER  = GND
  CM13  GND58  POWER  = GND
  CM17  PWR_1A_4  POWER  = P1V8_CPU1_RT3_1A
  CM20  PWR_1A_5  POWER  = P1V8_CPU1_RT3_1A
  CM22  GND59  POWER  = GND
  CM32  GND60  POWER  = GND
  CN2  GND62  POWER  = GND
  CN34  GND63  POWER  = GND
  CP1  GND64  POWER  = GND
  CP35  GND65  POWER  = GND
  CR7  B_PETP9  OUT  = P5E_CPU1_P3_TX_BUF_DP<6>
  CR26  A_PETP9  OUT  = P5E_CPU1_P3_RX_DP<6>
  CT2  A_PERN9  IN  = P5E_CPU1_P3_RX_BUF_DN<6>
  CT34  B_PERP9  IN  = P5E_CPU1_P3_TX_C_DN<6>
  CU10  B_PETN9  OUT  = P5E_CPU1_P3_TX_BUF_DN<6>
  CU29  A_PETN9  OUT  = P5E_CPU1_P3_RX_DN<6>
  CV1  A_PERP9  IN  = P5E_CPU1_P3_RX_BUF_DP<6>
  CV35  B_PERN9  IN  = P5E_CPU1_P3_TX_C_DP<6>
  CW4  GND69  POWER  = GND
  CW13  GND66  POWER  = GND
  CW17  PWR_2D_3  POWER  = P0V9_CPU1_RT_2D
  CW20  PWR_2D_4  POWER  = P0V9_CPU1_RT_2D
  CW22  GND67  POWER  = GND
  CW32  GND68  POWER  = GND
  CY2  GND70  POWER  = GND
  CY34  GND71  POWER  = GND
  D1  NCF_GND5  POWER  = NCF_CPU1_P3_GND
  D35  NCF_GND6  POWER  = NCF_CPU1_P3_GND
  DA1  GND72  POWER  = GND
  DA35  GND73  POWER  = GND
  DB7  B_PETP10  OUT  = P5E_CPU1_P3_TX_BUF_DP<5>
  DB26  A_PETP10  OUT  = P5E_CPU1_P3_RX_DP<5>
  DC2  A_PERN10  IN  = P5E_CPU1_P3_RX_BUF_DN<5>
  DC34  B_PERP10  IN  = P5E_CPU1_P3_TX_C_DN<5>
  DD10  B_PETN10  OUT  = P5E_CPU1_P3_TX_BUF_DN<5>
  DD29  A_PETN10  OUT  = P5E_CPU1_P3_RX_DN<5>
  DE1  A_PERP10  IN  = P5E_CPU1_P3_RX_BUF_DP<5>
  DE35  B_PERN10  IN  = P5E_CPU1_P3_TX_C_DP<5>
  DF4  GND77  POWER  = GND
  DF13  GND74  POWER  = GND
  DF17  PWR_2A_9  POWER  = P0V9_CPU1_RT3_2A_2D
  DF20  PWR_2A_10  POWER  = P0V9_CPU1_RT3_2A_2D
  DF22  GND75  POWER  = GND
  DF32  GND76  POWER  = GND
  DG2  GND78  POWER  = GND
  DG34  GND79  POWER  = GND
  DH1  GND80  POWER  = GND
  DH35  GND81  POWER  = GND
  DJ7  B_PETP11  OUT  = P5E_CPU1_P3_TX_BUF_DP<4>
  DJ26  A_PETP11  OUT  = P5E_CPU1_P3_RX_DP<4>
  DK2  A_PERN11  IN  = P5E_CPU1_P3_RX_BUF_DN<4>
  DK34  B_PERP11  IN  = P5E_CPU1_P3_TX_C_DN<4>
  DL10  B_PETN11  OUT  = P5E_CPU1_P3_TX_BUF_DN<4>
  DL29  A_PETN11  OUT  = P5E_CPU1_P3_RX_DN<4>
  DM1  A_PERP11  IN  = P5E_CPU1_P3_RX_BUF_DP<4>
  DM35  B_PERN11  IN  = P5E_CPU1_P3_TX_C_DP<4>
  DN4  GND85  POWER  = GND
  DN13  GND82  POWER  = GND
  DN17  PWR_2A_11  POWER  = P0V9_CPU1_RT3_2A
  DN20  PWR_2A_12  POWER  = P0V9_CPU1_RT3_2A
  DN22  GND83  POWER  = GND
  DN32  GND84  POWER  = GND
  DP2  GND86  POWER  = GND
  DP34  GND87  POWER  = GND
  DR1  GND88  POWER  = GND
  DR35  GND89  POWER  = GND
  DT7  B_PETP12  OUT  = P5E_CPU1_P3_TX_BUF_DP<3>
  DT26  A_PETP12  OUT  = P5E_CPU1_P3_RX_DP<3>
  DU2  A_PERN12  IN  = P5E_CPU1_P3_RX_BUF_DN<3>
  DU34  B_PERP12  IN  = P5E_CPU1_P3_TX_C_DN<3>
  DV10  B_PETN12  OUT  = P5E_CPU1_P3_TX_BUF_DN<3>
  DV29  A_PETN12  OUT  = P5E_CPU1_P3_RX_DN<3>
  DW1  A_PERP12  IN  = P5E_CPU1_P3_RX_BUF_DP<3>
  DW35  B_PERN12  IN  = P5E_CPU1_P3_TX_C_DP<3>
  DY4  GND93  POWER  = GND
  DY13  GND90  POWER  = GND
  DY17  PWR_2A_13  POWER  = P0V9_CPU1_RT3_2A
  DY20  PWR_2A_14  POWER  = P0V9_CPU1_RT3_2A
  DY22  GND91  POWER  = GND
  DY32  GND92  POWER  = GND
  E8  JTAG_TRST_N  IN  = JTAG_TRST_RT_CPU1_P3_N
  E11  RXDET_BYP  IN  = RXDET_BYP_RT_CPU1_P3
  E14  GND94  POWER  = GND
  E18  REFCLK_OUTN  OUT  = NC
  E27  GND95  POWER  = GND
  E30  T_SENSE  OUT  = GND
  E33  GND96  POWER  = GND
  EA2  GND97  POWER  = GND
  EA34  GND98  POWER  = GND
  EB1  GND99  POWER  = GND
  EB35  GND100  POWER  = GND
  EC7  B_PETP13  OUT  = P5E_CPU1_P3_TX_BUF_DP<2>
  EC26  A_PETP13  OUT  = P5E_CPU1_P3_RX_DP<2>
  ED2  A_PERN13  IN  = P5E_CPU1_P3_RX_BUF_DN<2>
  ED34  B_PERP13  IN  = P5E_CPU1_P3_TX_C_DN<2>
  EE10  B_PETN13  OUT  = P5E_CPU1_P3_TX_BUF_DN<2>
  EE29  A_PETN13  OUT  = P5E_CPU1_P3_RX_DN<2>
  EF1  A_PERP13  IN  = P5E_CPU1_P3_RX_BUF_DP<2>
  EF35  B_PERN13  IN  = P5E_CPU1_P3_TX_C_DP<2>
  EG4  GND104  POWER  = GND
  EG13  GND101  POWER  = GND
  EG17  PWR_2A_15  POWER  = P0V9_CPU1_RT3_2A
  EG20  PWR_2A_16  POWER  = P0V9_CPU1_RT3_2A
  EG22  GND102  POWER  = GND
  EG32  GND103  POWER  = GND
  EH2  GND105  POWER  = GND
  EH34  GND106  POWER  = GND
  EJ1  GND107  POWER  = GND
  EJ35  GND108  POWER  = GND
  EK7  B_PETP14  OUT  = P5E_CPU1_P3_TX_BUF_DP<1>
  EK26  A_PETP14  OUT  = P5E_CPU1_P3_RX_DP<1>
  EL2  A_PERN14  IN  = P5E_CPU1_P3_RX_BUF_DN<1>
  EL34  B_PERP14  IN  = P5E_CPU1_P3_TX_C_DP<1>
  EM10  B_PETN14  OUT  = P5E_CPU1_P3_TX_BUF_DN<1>
  EM29  A_PETN14  OUT  = P5E_CPU1_P3_RX_DN<1>
  EN1  A_PERP14  IN  = P5E_CPU1_P3_RX_BUF_DP<1>
  EN35  B_PERN14  IN  = P5E_CPU1_P3_TX_C_DN<1>
  EP4  GND112  POWER  = GND
  EP13  GND109  POWER  = GND
  EP17  PWR_2A_17  POWER  = P0V9_CPU1_RT3_2A
  EP20  PWR_2A_18  POWER  = P0V9_CPU1_RT3_2A
  EP22  GND110  POWER  = GND
  EP32  GND111  POWER  = GND
  ER2  GND113  POWER  = GND
  ER34  GND114  POWER  = GND
  ET1  GND115  POWER  = GND
  ET35  GND116  POWER  = GND
  EU7  B_PETP15  OUT  = P5E_CPU1_P3_TX_BUF_DP<0>
  EU26  A_PETP15  OUT  = P5E_CPU1_P3_RX_DP<0>
  EV2  A_PERN15  IN  = P5E_CPU1_P3_RX_BUF_DN<0>
  EV34  B_PERP15  IN  = P5E_CPU1_P3_TX_C_DN<0>
  EW10  B_PETN15  OUT  = P5E_CPU1_P3_TX_BUF_DN<0>
  EW29  A_PETN15  OUT  = P5E_CPU1_P3_RX_DN<0>
  EY1  A_PERP15  IN  = P5E_CPU1_P3_RX_BUF_DP<0>
  EY35  B_PERN15  IN  = P5E_CPU1_P3_TX_C_DP<0>
  F2  PERST_N  IN  = RST_RT_CPU1_P3_PERST_N
  F34  SMB_ADDR1  IN  = RT_CPU1_P3_ADDR1
  FA15  GND117  POWER  = GND
  FA32  GND118  POWER  = GND
  FB2  GND119  POWER  = GND
  FB34  GND120  POWER  = GND
  FC3  GND125  POWER  = GND
  FC6  GND126  POWER  = GND
  FC9  GND127  POWER  = GND
  FC19  GND121  POWER  = GND
  FC23  GND122  POWER  = GND
  FC25  GND123  POWER  = GND
  FC28  GND124  POWER  = GND
  FD1  GND128  POWER  = GND
  FD35  GND129  POWER  = GND
  FE2  NCF_GND7  POWER  = NCF_CPU1_P3_GND
  FE34  NCF_GND8  POWER  = NCF_CPU1_P3_GND
  FF5  EE_CLK  BI  = SMB_RT_CPU1_P3_ROM_MUX_1D_R_SCL
  FF8  JTAG_TEST_MODE  IN  = JTAG_TEST_MODE_RT_CPU1_P3
  FF11  RESET_N  IN  = RST_RT_CPU1_P3_RESET_N
  FF14  GND130  POWER  = GND
  FF18  REFCLKN  IN  = CLK_100M_RETIMER_CPU1_P3_DN
  FF21  GND131  POWER  = GND
  FF24  TEST0  BI  = TEST0_RT_CPU1_P3
  FF27  TEST1  BI  = TEST1_RT_CPU1_P3
  FF30  TEST2  BI  = TEST2_RT_CPU1_P3
  FF33  SCAN_MODE  IN  = RT_CPU1_P3_SCAN_MODE
  FG1  NCF_GND9  POWER  = NCF_CPU1_P3_GND
  FG35  NCF_GND10  POWER  = NCF_CPU1_P3_GND
  FH2  NCF_GND11  POWER  = NCF_CPU1_P3_GND
  FH34  NCF_GND12  POWER  = NCF_CPU1_P3_GND
  FJ3  EE_DAT  BI  = SMB_RT_CPU1_P3_ROM_MUX_1D_R_SDA
  FJ6  GPIO0  BI  = NC
  FJ9  MODE  IN  = MODE_RT_CPU1_P3
  FJ12  GND132  POWER  = GND
  FJ16  REFCLKP  IN  = CLK_100M_RETIMER_CPU1_P3_DP
  FJ19  GND133  POWER  = GND
  FJ23  GPIO1  BI  = NC
  FJ25  GPIO2  BI  = GPIO2_RT_CPU1_P3
  FJ28  GPIO3  BI  = GPIO3_RT_CPU1_P3
  FJ31  INT_N  OUT  = NC
  G1  VQPS  IN  = RT_CPU1_P3_VQPS
  G35  CLKREQ_N  IN  = CLKREQ_RT_CPU1_P3_N
  H12  GND134  POWER  = GND
  H16  GND135  POWER  = GND
  H19  GND136  POWER  = GND
  H31  GND137  POWER  = GND
  J4  GND139  POWER  = GND
  J22  GND138  POWER  = GND
  K2  GND140  POWER  = GND
  K34  GND141  POWER  = GND
  L1  GND142  POWER  = GND
  L35  GND143  POWER  = GND
  M7  B_PETP0  OUT  = P5E_CPU1_P3_TX_BUF_DP<15>
  M26  A_PETP0  OUT  = P5E_CPU1_P3_RX_DP<15>
  N2  A_PERN0  IN  = P5E_CPU1_P3_RX_BUF_DN<15>
  N34  B_PERP0  IN  = P5E_CPU1_P3_TX_C_DN<15>
  P10  B_PETN0  OUT  = P5E_CPU1_P3_TX_BUF_DN<15>
  P29  A_PETN0  OUT  = P5E_CPU1_P3_RX_DN<15>
  R1  A_PERP0  IN  = P5E_CPU1_P3_RX_BUF_DP<15>
  R35  B_PERN0  IN  = P5E_CPU1_P3_TX_C_DP<15>
  T4  GND147  POWER  = GND
  T13  GND144  POWER  = GND
  T17  PWR_2A_19  POWER  = P0V9_CPU1_RT3_2A
  T20  PWR_2A_20  POWER  = P0V9_CPU1_RT3_2A
  T22  GND145  POWER  = GND
  T32  GND146  POWER  = GND
  U2  GND148  POWER  = GND
  U34  GND149  POWER  = GND
  V1  GND150  POWER  = GND
  V35  GND151  POWER  = GND
  W7  B_PETP1  OUT  = P5E_CPU1_P3_TX_BUF_DP<14>
  W26  A_PETP1  OUT  = P5E_CPU1_P3_RX_DP<14>
  Y2  A_PERN1  IN  = P5E_CPU1_P3_RX_BUF_DN<14>
  Y34  B_PERP1  IN  = P5E_CPU1_P3_TX_C_DP<14>

U6020  TCA9548APWR  IC  pkg TSSOP24XA  page 184
  1  A0  IN  = RT_SMB_MUX_ADDR0
  2  A1  IN  = RT_SMB_MUX_ADDR1
  3  \reset#\  IN  = RST_SMB_RT_N
  4  SD0  BI  = SMB_RT_CPU1_P0_SDA
  5  SC0  BI  = SMB_RT_CPU1_P0_SCL
  6  SD1  BI  = SMB_RT_CPU1_P1_SDA
  7  SC1  BI  = SMB_RT_CPU1_P1_SCL
  8  SD2  BI  = SMB_RT_CPU1_P3_SDA
  9  SC2  BI  = SMB_RT_CPU1_P3_SCL
  10  SD3  BI  = SMB_RT_CPU1_P2_SDA
  11  SC3  BI  = SMB_RT_CPU1_P2_SCL
  12  GND  POWER  = GND
  13  SD4  BI  = SMB_RT_CPU0_P0_SDA
  14  SC4  BI  = SMB_RT_CPU0_P0_SCL
  15  SD5  BI  = SMB_RT_CPU0_P1_SDA
  16  SC5  BI  = SMB_RT_CPU0_P1_SCL
  17  SD6  BI  = SMB_RT_CPU0_P3_SDA
  18  SC6  BI  = SMB_RT_CPU0_P3_SCL
  19  SD7  BI  = SMB_RT_CPU0_P2_SDA
  20  SC7  BI  = SMB_RT_CPU0_P2_SCL
  21  A2  IN  = RT_SMB_MUX_ADDR2
  22  SCL  BI  = SMB_MUX_RT_SCL
  23  SDA  BI  = SMB_MUX_RT_SDA
  24  VCC  POWER  = P1V8_AUX

U8000  NC7SB3157P6X  IC  pkg SC70-6XA  page 153
  1  B1  BI  = ESPI_CPU0_ALERT_R1_N
  2  GND  POWER  = GND
  3  B0  BI  = ESPI_CPU0_ALERT_PLD_N
  4  A  BI  = ESPI_CPU0_ALERT_P0_N
  5  VCC  POWER  = P1V8_AUX
  6  S  IN  = FM_ESPI_CPU0_ALERT_R_SEL

U8001  APX80929SAG7  APX809-29SAG-7 IC  pkg SOT23_123XI  page 136
  1  GND  POWER  = GND
  2  RESET_L  OUT  = OCP_V3_1_P3V3_R1_PWRGD
  3  VCC  POWER  = P3V3_OCP_SFF_R
